FILE_TYPE = MULTI_PHYS_TABLE;

PART 'RAA2213404GNPHB0'

{========================================================================================}
:VALUE               | PART_TYPE | MATERIAL | PART_NUMBER    = STANDARD        | LIFECYCLE          | PART_NUMBER   | JEDEC_TYPE      | DESCRIPTION                             | MANUFTR | MANUF_PN            | RD_CMPLS_LVL | CMPLS_LVL | FROM_PJ    | CLASS | DIP_SMD | DATA                       | EE_CHECK_LIST | FP_ECN                 | PSL | CREATOR | STATUS | MSD  | ESD_CDM | ESD_HBM | ESD_MM | PIN_LENGTH_SHORT_PIN | PIN_LENGTH_LONG_PIN | CREATEDAY  ;
{========================================================================================}
 'RAA2213404GNP#HB0' | 'SMLF'    | 'IC'     | 'AL221340000'(!) = 'Non-Preferred'  | 'End of Life'    | 'AL221340000' |'PQFN17_TH_5X4_EOL'| 'IC OTHER(29P) RAA2213404GNP#HB0(PQFN)' | 'RTT'   | 'RAA2213404GNP#HB0' | 'EP(V1)'     | ''        | 'S9S-KIMI' | 'IC'  | ''      | 'RTT_RAA2213404GNPHB0.pdf' | ''            | 'RAA2213404GNPHB0.msg' | ''  | ''      | ''     | 'NA' | 'NA'    | 'NA'    | 'NA'   | '0 MILS'             | '0 MILS'            | '20200316'
 'RAA2213404GNP#HB0' | 'SMLF'    | 'EMPTY'  | 'AL221340000'(!) = 'Non-Preferred'  | 'End of Life'    | 'AL221340000' |'PQFN17_TH_5X4_EOL'| 'IC OTHER(29P) RAA2213404GNP#HB0(PQFN)' | 'RTT'   | 'RAA2213404GNP#HB0' | 'EP(V1)'     | ''        | 'S9S-KIMI' | 'IC'  | ''      | 'RTT_RAA2213404GNPHB0.pdf' | ''            | 'RAA2213404GNPHB0.msg' | ''  | ''      | ''     | 'NA' | 'NA'    | 'NA'    | 'NA'   | '0 MILS'             | '0 MILS'            | '20200316'
 'RAA2213404GNP#HB0' | 'SMLF'    | 'IC'     | 'AL221340002'(!) = ''               | ''               | 'AL221340002' |'PQFN17_TH_5X4'| 'IC (29P) RAA2213404GNP#HB0(PQFN)'      | 'RTT'   | 'RAA2213404GNP#HB0' | 'EP(V1)'     | ''        | 'S6Q-KIMI' | 'IC'  | ''      | 'RTT_RAA2213404GNPHB0.pdf' | ''            | 'RAA2213404GNPHB0.msg' | ''  | ''      | ''     | 'NA' | 'NA'    | 'NA'    | 'NA'   | '0 MILS'             | '0 MILS'            | '20201006'
 'RAA2213404GNP#HB0' | 'SMLF'    | 'EMPTY'  | 'AL221340002'(!) = ''               | ''               | 'AL221340002' |'PQFN17_TH_5X4'| 'IC (29P) RAA2213404GNP#HB0(PQFN)'      | 'RTT'   | 'RAA2213404GNP#HB0' | 'EP(V1)'     | ''        | 'S6Q-KIMI' | 'IC'  | ''      | 'RTT_RAA2213404GNPHB0.pdf' | ''            | 'RAA2213404GNPHB0.msg' | ''  | ''      | ''     | 'NA' | 'NA'    | 'NA'    | 'NA'   | '0 MILS'             | '0 MILS'            | '20201006'

END_PART

END.

